# T6G (Grand Teton) — schematic netlist excerpt (pin names and nets, part order shuffled) for the footprints in the layout excerpt that follows; sources: Cadence DE-HDL packaged netlist, KiCad conversion of 04192023_DAF0TMB3IC0_F0TG_MB_C_brd_V02_OCP.brd

C2618  Q_CAP  22UF 4V 20% X6S  pkg C0402  page 70 : A = PVDDIO_P0 ; B = GND
R585  Q_RES  10K 1% CHIP  pkg 0402LF  page 183 : A = CLK_9ZXL045_P1_HIBW ; B = GND
C294  Q_CAP  1UF 4V 20% X6S  pkg 0201  page 334 : A = P0V9_CPU1_RT1_2A ; B = GND

(kicad_pcb
	(version 20260206)
	(generator "pcbnew")
	(generator_version "10.0")
	(general
		(thickness 1.6)
		(legacy_teardrops no)
	)
	(paper "A4")
	(title_block
		(title "04192023_DAF0TMB3IC0_F0TG_MB_C_brd_V02_OCP.brd")
		(comment 1 "Grand Teton / footprints 4999-5001 of 8354")
	)
	(layers
		(0 "F.Cu" signal "TOP")
		(4 "In1.Cu" signal "GND")
		(6 "In2.Cu" signal "IN1")
		(8 "In3.Cu" signal "GND1")
		(10 "In4.Cu" signal "IN2")
		(12 "In5.Cu" signal "GND2")
		(14 "In6.Cu" signal "IN3")
		(16 "In7.Cu" signal "GND3")
		(18 "In8.Cu" signal "VCC")
		(20 "In9.Cu" signal "VCC1")
		(22 "In10.Cu" signal "GND4")
		(24 "In11.Cu" signal "IN4")
		(26 "In12.Cu" signal "GND5")
		(28 "In13.Cu" signal "IN5")
		(30 "In14.Cu" signal "GND6")
		(32 "In15.Cu" signal "IN6")
		(34 "In16.Cu" signal "GND7")
		(2 "B.Cu" signal "BOTTOM")
		(9 "F.Adhes" user "F.Adhesive")
		(11 "B.Adhes" user "B.Adhesive")
		(13 "F.Paste" user "Package Geometry/Pastemask Top")
		(15 "B.Paste" user "Package Geometry/Pastemask Bottom")
		(5 "F.SilkS" user "Ref Des/Silkscreen Top")
		(7 "B.SilkS" user "Ref Des/Silkscreen Bottom")
		(1 "F.Mask" user "Board Geometry/Soldermask Top")
		(3 "B.Mask" user "Board Geometry/Soldermask Bottom")
		(17 "Dwgs.User" user "User.Drawings")
		(19 "Cmts.User" user "User.Comments")
		(21 "Eco1.User" user "User.Eco1")
		(23 "Eco2.User" user "User.Eco2")
		(25 "Edge.Cuts" user "Board Geometry/Outline")
		(27 "Margin" user)
		(31 "F.CrtYd" user "Package Geometry/Place Bound Top")
		(29 "B.CrtYd" user "Package Geometry/Place Bound Bottom")
		(35 "F.Fab" user "Ref Des/Assembly Top")
		(33 "B.Fab" user "Ref Des/Assembly Bottom")
	)
	(footprint ""
		(layer "B.Cu")
		(at 111.125 -413.004)
		(property "Reference" "R585"
			(at 0 0 0)
			(layer "B.SilkS")
			(hide yes)
			(effects
				(font
					(size 1.27 1.27)
				)
				(justify mirror)
			)
		)
		(property "Value" ""
			(at 0 0 0)
			(layer "B.Fab")
			(effects
				(font
					(size 1.27 1.27)
				)
				(justify mirror)
			)
		)
		(duplicate_pad_numbers_are_jumpers no)
		(fp_line
			(start -0.7874 -0.4064)
			(end -0.7874 0.4064)
			(stroke
				(width 0.1524)
				(type default)
			)
			(layer "B.SilkS")
		)
		(fp_line
			(start -0.7874 0.4064)
			(end 0.7874 0.4064)
			(stroke
				(width 0.1524)
				(type default)
			)
			(layer "B.SilkS")
		)
		(fp_line
			(start 0.7874 -0.4064)
			(end -0.7874 -0.4064)
			(stroke
				(width 0.1524)
				(type default)
			)
			(layer "B.SilkS")
		)
		(fp_line
			(start 0.7874 0.4064)
			(end 0.7874 -0.4064)
			(stroke
				(width 0.1524)
				(type default)
			)
			(layer "B.SilkS")
		)
		(fp_line
			(start -0.67945 -0.3048)
			(end -0.67945 0.3048)
			(stroke
				(width 0.1)
				(type default)
			)
			(layer "B.Fab")
		)
		(fp_line
			(start -0.67945 0.3048)
			(end -0.120396 0.3048)
			(stroke
				(width 0.1)
				(type default)
			)
			(layer "B.Fab")
		)
		(fp_line
			(start -0.12065 -0.3048)
			(end -0.67945 -0.3048)
			(stroke
				(width 0.1)
				(type default)
			)
			(layer "B.Fab")
		)
		(fp_line
			(start -0.12065 -0.2794)
			(end -0.12065 -0.3048)
			(stroke
				(width 0.1)
				(type default)
			)
			(layer "B.Fab")
		)
		(fp_line
			(start -0.120396 0.2794)
			(end 0.12065 0.2794)
			(stroke
				(width 0.1)
				(type default)
			)
			(layer "B.Fab")
		)
		(fp_line
			(start -0.120396 0.3048)
			(end -0.120396 0.2794)
			(stroke
				(width 0.1)
				(type default)
			)
			(layer "B.Fab")
		)
		(fp_line
			(start 0.12065 -0.305054)
			(end 0.12065 -0.2794)
			(stroke
				(width 0.1)
				(type default)
			)
			(layer "B.Fab")
		)
		(fp_line
			(start 0.12065 -0.2794)
			(end -0.12065 -0.2794)
			(stroke
				(width 0.1)
				(type default)
			)
			(layer "B.Fab")
		)
		(fp_line
			(start 0.12065 0.2794)
			(end 0.12065 0.3048)
			(stroke
				(width 0.1)
				(type default)
			)
			(layer "B.Fab")
		)
		(fp_line
			(start 0.12065 0.3048)
			(end 0.67945 0.3048)
			(stroke
				(width 0.1)
				(type default)
			)
			(layer "B.Fab")
		)
		(fp_line
			(start 0.67945 -0.305054)
			(end 0.12065 -0.305054)
			(stroke
				(width 0.1)
				(type default)
			)
			(layer "B.Fab")
		)
		(fp_line
			(start 0.67945 0.3048)
			(end 0.67945 -0.305054)
			(stroke
				(width 0.1)
				(type default)
			)
			(layer "B.Fab")
		)
		(pad "1" smd circle
			(at 0.40005 0 180)
			(size 0 0)
			(layers "B.Cu" "B.Mask" "B.Paste")
			(net "CLK_9ZXL045_P1_HIBW")
		)
		(pad "2" smd circle
			(at -0.40005 0 180)
			(size 0 0)
			(layers "B.Cu" "B.Mask" "B.Paste")
			(net "GND")
		)
	)
	(footprint ""
		(layer "B.Cu")
		(at 346.518992 -257.930142 180)
		(property "Reference" "C2618"
			(at 0 0 0)
			(layer "B.SilkS")
			(hide yes)
			(effects
				(font
					(size 1.27 1.27)
				)
				(justify mirror)
			)
		)
		(property "Value" ""
			(at 0 0 0)
			(layer "B.Fab")
			(effects
				(font
					(size 1.27 1.27)
				)
				(justify mirror)
			)
		)
		(duplicate_pad_numbers_are_jumpers no)
		(fp_line
			(start 0.7874 0.4064)
			(end 0.7874 -0.4064)
			(stroke
				(width 0.1524)
				(type default)
			)
			(layer "B.SilkS")
		)
		(fp_line
			(start 0.7874 -0.4064)
			(end -0.7874 -0.4064)
			(stroke
				(width 0.1524)
				(type default)
			)
			(layer "B.SilkS")
		)
		(fp_line
			(start -0.7874 0.4064)
			(end 0.7874 0.4064)
			(stroke
				(width 0.1524)
				(type default)
			)
			(layer "B.SilkS")
		)
		(fp_line
			(start -0.7874 -0.4064)
			(end -0.7874 0.4064)
			(stroke
				(width 0.1524)
				(type default)
			)
			(layer "B.SilkS")
		)
		(fp_line
			(start 0.67945 0.3048)
			(end 0.67945 -0.305054)
			(stroke
				(width 0.1)
				(type default)
			)
			(layer "B.Fab")
		)
		(fp_line
			(start 0.67945 -0.305054)
			(end 0.12065 -0.305054)
			(stroke
				(width 0.1)
				(type default)
			)
			(layer "B.Fab")
		)
		(fp_line
			(start 0.12065 0.3048)
			(end 0.67945 0.3048)
			(stroke
				(width 0.1)
				(type default)
			)
			(layer "B.Fab")
		)
		(fp_line
			(start 0.12065 0.2794)
			(end 0.12065 0.3048)
			(stroke
				(width 0.1)
				(type default)
			)
			(layer "B.Fab")
		)
		(fp_line
			(start 0.12065 -0.2794)
			(end -0.12065 -0.2794)
			(stroke
				(width 0.1)
				(type default)
			)
			(layer "B.Fab")
		)
		(fp_line
			(start 0.12065 -0.305054)
			(end 0.12065 -0.2794)
			(stroke
				(width 0.1)
				(type default)
			)
			(layer "B.Fab")
		)
		(fp_line
			(start -0.120396 0.3048)
			(end -0.120396 0.2794)
			(stroke
				(width 0.1)
				(type default)
			)
			(layer "B.Fab")
		)
		(fp_line
			(start -0.120396 0.2794)
			(end 0.12065 0.2794)
			(stroke
				(width 0.1)
				(type default)
			)
			(layer "B.Fab")
		)
		(fp_line
			(start -0.12065 -0.2794)
			(end -0.12065 -0.3048)
			(stroke
				(width 0.1)
				(type default)
			)
			(layer "B.Fab")
		)
		(fp_line
			(start -0.12065 -0.3048)
			(end -0.67945 -0.3048)
			(stroke
				(width 0.1)
				(type default)
			)
			(layer "B.Fab")
		)
		(fp_line
			(start -0.67945 0.3048)
			(end -0.120396 0.3048)
			(stroke
				(width 0.1)
				(type default)
			)
			(layer "B.Fab")
		)
		(fp_line
			(start -0.67945 -0.3048)
			(end -0.67945 0.3048)
			(stroke
				(width 0.1)
				(type default)
			)
			(layer "B.Fab")
		)
		(pad "1" smd circle
			(at 0.40005 0)
			(size 0 0)
			(layers "B.Cu" "B.Mask" "B.Paste")
			(net "PVDDIO_P0")
		)
		(pad "2" smd circle
			(at -0.40005 0)
			(size 0 0)
			(layers "B.Cu" "B.Mask" "B.Paste")
			(net "GND")
		)
	)
	(footprint ""
		(layer "B.Cu")
		(at 83.50631 -386.766562 90)
		(property "Reference" "C294"
			(at 0 0 90)
			(layer "B.SilkS")
			(hide yes)
			(effects
				(font
					(size 1.27 1.27)
				)
				(justify mirror)
			)
		)
		(property "Value" ""
			(at 0 0 90)
			(layer "B.Fab")
			(effects
				(font
					(size 1.27 1.27)
				)
				(justify mirror)
			)
		)
		(duplicate_pad_numbers_are_jumpers no)
		(fp_line
			(start 0.299974 -0.150114)
			(end -0.299974 -0.150114)
			(stroke
				(width 0.1)
				(type default)
			)
			(layer "B.Fab")
		)
		(fp_line
			(start -0.299974 -0.150114)
			(end -0.299974 0.150114)
			(stroke
				(width 0.1)
				(type default)
			)
			(layer "B.Fab")
		)
		(fp_line
			(start 0.299974 0.150114)
			(end 0.299974 -0.150114)
			(stroke
				(width 0.1)
				(type default)
			)
			(layer "B.Fab")
		)
		(fp_line
			(start -0.299974 0.150114)
			(end 0.299974 0.150114)
			(stroke
				(width 0.1)
				(type default)
			)
			(layer "B.Fab")
		)
		(pad "1" smd rect
			(at 0.2667 0 270)
			(size 0.3048 0.381)
			(layers "B.Cu" "B.Mask" "B.Paste")
			(net "P0V9_CPU1_RT1_2A")
		)
		(pad "2" smd rect
			(at -0.2667 0 270)
			(size 0.3048 0.381)
			(layers "B.Cu" "B.Mask" "B.Paste")
			(net "GND")
		)
	)
)
